(kicad_pcb
	(version 20241229)
	(generator "pcbnew")
	(generator_version "9.0")
	(general
		(thickness 1.61)
		(legacy_teardrops no)
	)
	(paper "A3")
	(title_block
		(title "RDIMM DDR5 Tester")
		(date "2026-05-21")
		(rev "2.2.0")
		(company "Antmicro")
		(comment 9 "footprints 765-769 of 796")
	)
	(layers
		(0 "F.Cu" signal)
		(4 "In1.Cu" power)
		(6 "In2.Cu" mixed)
		(8 "In3.Cu" power)
		(10 "In4.Cu" mixed)
		(12 "In5.Cu" power)
		(14 "In6.Cu" mixed)
		(16 "In7.Cu" power)
		(18 "In8.Cu" power)
		(20 "In9.Cu" mixed)
		(22 "In10.Cu" power)
		(2 "B.Cu" signal)
		(9 "F.Adhes" user "F.Adhesive")
		(11 "B.Adhes" user "B.Adhesive")
		(13 "F.Paste" user)
		(15 "B.Paste" user)
		(5 "F.SilkS" user "F.Silkscreen")
		(7 "B.SilkS" user "B.Silkscreen")
		(1 "F.Mask" user)
		(3 "B.Mask" user)
		(17 "Dwgs.User" user "User.Drawings")
		(19 "Cmts.User" user "User.Comments")
		(21 "Eco1.User" user "User.Eco1")
		(23 "Eco2.User" user "User.Eco2")
		(25 "Edge.Cuts" user)
		(27 "Margin" user)
		(31 "F.CrtYd" user "F.Courtyard")
		(29 "B.CrtYd" user "B.Courtyard")
		(35 "F.Fab" user)
		(33 "B.Fab" user)
	)
	(footprint "antmicro-footprints:C_0402_1005Metric"
		(layer "B.Cu")
		(at 113.991885 127.08 90)
		(descr "Capacitor SMD 0402")
		(tags "capacitor SMD 0402")
		(property "Reference" "C137"
			(at 0.894487 0.464604 90)
			(layer "B.SilkS")
			(effects
				(font
					(size 0.7 0.7)
					(thickness 0.15)
				)
				(justify right bottom mirror)
			)
		)
		(property "Value" "C_100n_0402"
			(at -1.022927 -2.155213 90)
			(layer "B.Fab")
			(effects
				(font
					(size 0.7 0.7)
					(thickness 0.15)
				)
				(justify right bottom mirror)
			)
		)
		(property "Datasheet" "https://www.murata.com/products/productdetail?partno=GRM155R61H104KE14%23"
			(at 0 0 90)
			(layer "F.Fab")
			(hide yes)
			(effects
				(font
					(size 1.27 1.27)
					(thickness 0.15)
				)
			)
		)
		(property "MPN" "GRM155R61H104KE14D"
			(at 0 0 90)
			(unlocked yes)
			(layer "B.Fab")
			(hide yes)
			(effects
				(font
					(size 1 1)
					(thickness 0.15)
				)
				(justify mirror)
			)
		)
		(property "Manufacturer" "Murata"
			(at 0 0 90)
			(unlocked yes)
			(layer "B.Fab")
			(hide yes)
			(effects
				(font
					(size 1 1)
					(thickness 0.15)
				)
				(justify mirror)
			)
		)
		(property "License" "Apache-2.0"
			(at 0 0 90)
			(unlocked yes)
			(layer "B.Fab")
			(hide yes)
			(effects
				(font
					(size 1 1)
					(thickness 0.15)
				)
				(justify mirror)
			)
		)
		(property "Author" "Antmicro"
			(at 0 0 90)
			(unlocked yes)
			(layer "B.Fab")
			(hide yes)
			(effects
				(font
					(size 1 1)
					(thickness 0.15)
				)
				(justify mirror)
			)
		)
		(property "Val" "100n"
			(at 0 0 90)
			(unlocked yes)
			(layer "B.Fab")
			(hide yes)
			(effects
				(font
					(size 1 1)
					(thickness 0.15)
				)
				(justify mirror)
			)
		)
		(property "Voltage" "50V"
			(at 0 0 90)
			(unlocked yes)
			(layer "B.Fab")
			(hide yes)
			(effects
				(font
					(size 1 1)
					(thickness 0.15)
				)
				(justify mirror)
			)
		)
		(property "Dielectric" "X5R"
			(at 0 0 90)
			(unlocked yes)
			(layer "B.Fab")
			(hide yes)
			(effects
				(font
					(size 1 1)
					(thickness 0.15)
				)
				(justify mirror)
			)
		)
		(sheetname "/Ethernet/")
		(sheetfile "ethernet.kicad_sch")
		(attr smd)
		(fp_rect
			(start -0.925 0.47)
			(end 0.925 -0.47)
			(stroke
				(width 0.05)
				(type default)
			)
			(fill no)
			(layer "B.CrtYd")
		)
		(fp_line
			(start 0.504 -0.248)
			(end -0.494 -0.248)
			(stroke
				(width 0.15)
				(type solid)
			)
			(layer "B.Fab")
		)
		(fp_line
			(start -0.494 -0.248)
			(end -0.494 0.25)
			(stroke
				(width 0.15)
				(type solid)
			)
			(layer "B.Fab")
		)
		(fp_line
			(start 0.504 0.25)
			(end 0.504 -0.248)
			(stroke
				(width 0.15)
				(type solid)
			)
			(layer "B.Fab")
		)
		(fp_line
			(start -0.494 0.25)
			(end 0.504 0.25)
			(stroke
				(width 0.15)
				(type solid)
			)
			(layer "B.Fab")
		)
		(fp_text user "${REFERENCE}"
			(at -0.939 -4.599 270)
			(layer "B.Fab")
			(effects
				(font
					(size 0.7 0.7)
					(thickness 0.15)
				)
				(justify left bottom mirror)
			)
		)
		(fp_text user "License: Apache-2.0"
			(at -0.939 -5.799 270)
			(layer "B.Fab")
			(effects
				(font
					(size 0.7 0.7)
					(thickness 0.15)
				)
				(justify left bottom mirror)
			)
		)
		(fp_text user "Author: Antmicro"
			(at -0.939 -3.399 270)
			(layer "B.Fab")
			(effects
				(font
					(size 0.7 0.7)
					(thickness 0.15)
				)
				(justify left bottom mirror)
			)
		)
		(pad "1" smd roundrect
			(at -0.48 0 90)
			(size 0.59 0.64)
			(layers "B.Cu" "B.Mask" "B.Paste")
			(roundrect_rratio 0.25)
			(net 1 "GND")
			(pintype "passive")
		)
		(pad "2" smd roundrect
			(at 0.48 0 90)
			(size 0.59 0.64)
			(layers "B.Cu" "B.Mask" "B.Paste")
			(roundrect_rratio 0.25)
			(net 822 "Net-(C137-Pad2)")
			(pintype "passive")
		)
	)
	(footprint "antmicro-footprints:C_0402_1005Metric_EIA"
		(layer "B.Cu")
		(at 194 154.5 90)
		(descr "Capacitor SMD 0402 (1005 Metric), square (rectangular) end terminal, IPC_7351 nominal, (Body size source: IPC-SM-782 page 76, https://www.pcb-3d.com/wordpress/wp-content/uploads/ipc-sm-782a_amendment_1_and_2.pdf)")
		(tags "capacitor 0402")
		(property "Reference" "C42"
			(at 9.8 -30.65 90)
			(layer "B.SilkS")
			(effects
				(font
					(size 0.7 0.7)
					(thickness 0.15)
				)
				(justify right bottom mirror)
			)
		)
		(property "Value" "C_100n_0402"
			(at 0 -1.169 90)
			(layer "B.Fab")
			(effects
				(font
					(size 0.7 0.7)
					(thickness 0.15)
				)
				(justify right bottom mirror)
			)
		)
		(property "Datasheet" "https://www.murata.com/products/productdetail?partno=GRM155R61H104KE14%23"
			(at 0 0 90)
			(layer "F.Fab")
			(hide yes)
			(effects
				(font
					(size 1.27 1.27)
					(thickness 0.15)
				)
			)
		)
		(property "MPN" "GRM155R61H104KE14D"
			(at 0 0 90)
			(unlocked yes)
			(layer "B.Fab")
			(hide yes)
			(effects
				(font
					(size 1 1)
					(thickness 0.15)
				)
				(justify mirror)
			)
		)
		(property "Manufacturer" "Murata"
			(at 0 0 90)
			(unlocked yes)
			(layer "B.Fab")
			(hide yes)
			(effects
				(font
					(size 1 1)
					(thickness 0.15)
				)
				(justify mirror)
			)
		)
		(property "License" "Apache-2.0"
			(at 0 0 90)
			(unlocked yes)
			(layer "B.Fab")
			(hide yes)
			(effects
				(font
					(size 1 1)
					(thickness 0.15)
				)
				(justify mirror)
			)
		)
		(property "Author" "Antmicro"
			(at 0 0 90)
			(unlocked yes)
			(layer "B.Fab")
			(hide yes)
			(effects
				(font
					(size 1 1)
					(thickness 0.15)
				)
				(justify mirror)
			)
		)
		(property "Val" "100n"
			(at 0 0 90)
			(unlocked yes)
			(layer "B.Fab")
			(hide yes)
			(effects
				(font
					(size 1 1)
					(thickness 0.15)
				)
				(justify mirror)
			)
		)
		(property "Voltage" "50V"
			(at 0 0 90)
			(unlocked yes)
			(layer "B.Fab")
			(hide yes)
			(effects
				(font
					(size 1 1)
					(thickness 0.15)
				)
				(justify mirror)
			)
		)
		(property "Dielectric" "X5R"
			(at 0 0 90)
			(unlocked yes)
			(layer "B.Fab")
			(hide yes)
			(effects
				(font
					(size 1 1)
					(thickness 0.15)
				)
				(justify mirror)
			)
		)
		(sheetname "/FPGA power/")
		(sheetfile "fpga-power.kicad_sch")
		(attr smd)
		(fp_rect
			(start -0.95 0.45)
			(end 0.95 -0.45)
			(stroke
				(width 0.05)
				(type default)
			)
			(fill no)
			(layer "B.CrtYd")
		)
		(fp_line
			(start 0.498 -0.248)
			(end -0.5 -0.248)
			(stroke
				(width 0.15)
				(type solid)
			)
			(layer "B.Fab")
		)
		(fp_line
			(start -0.5 -0.248)
			(end -0.5 0.25)
			(stroke
				(width 0.15)
				(type solid)
			)
			(layer "B.Fab")
		)
		(fp_line
			(start 0.498 0.25)
			(end 0.498 -0.248)
			(stroke
				(width 0.15)
				(type solid)
			)
			(layer "B.Fab")
		)
		(fp_line
			(start -0.5 0.25)
			(end 0.498 0.25)
			(stroke
				(width 0.15)
				(type solid)
			)
			(layer "B.Fab")
		)
		(fp_text user "License: Apache-2.0"
			(at -0.9656 -4.369 270)
			(layer "B.Fab")
			(effects
				(font
					(size 0.7 0.7)
					(thickness 0.15)
				)
				(justify left bottom mirror)
			)
		)
		(fp_text user "${REFERENCE}"
			(at -0.9656 -3.169 270)
			(layer "B.Fab")
			(effects
				(font
					(size 0.7 0.7)
					(thickness 0.15)
				)
				(justify left bottom mirror)
			)
		)
		(fp_text user "Author: Antmicro"
			(at -0.9656 -5.569 270)
			(layer "B.Fab")
			(effects
				(font
					(size 0.7 0.7)
					(thickness 0.15)
				)
				(justify left bottom mirror)
			)
		)
		(pad "1" smd roundrect
			(at -0.5 0)
			(size 0.6 0.6)
			(layers "B.Cu" "B.Mask" "B.Paste")
			(roundrect_rratio 0.25)
			(net 1 "GND")
			(pintype "passive")
		)
		(pad "2" smd roundrect
			(at 0.498 0 90)
			(size 0.6 0.6)
			(layers "B.Cu" "B.Mask" "B.Paste")
			(roundrect_rratio 0.25)
			(net 553 "+0V85")
			(pintype "passive")
		)
	)
	(footprint "antmicro-footprints:C_0402_1005Metric_EIA"
		(layer "B.Cu")
		(at 186 160.5 90)
		(descr "Capacitor SMD 0402 (1005 Metric), square (rectangular) end terminal, IPC_7351 nominal, (Body size source: IPC-SM-782 page 76, https://www.pcb-3d.com/wordpress/wp-content/uploads/ipc-sm-782a_amendment_1_and_2.pdf)")
		(tags "capacitor 0402")
		(property "Reference" "C101"
			(at 8.725 -30.725 90)
			(layer "B.SilkS")
			(effects
				(font
					(size 0.7 0.7)
					(thickness 0.15)
				)
				(justify right bottom mirror)
			)
		)
		(property "Value" "C_100n_0402"
			(at 0 -1.169 90)
			(layer "B.Fab")
			(effects
				(font
					(size 0.7 0.7)
					(thickness 0.15)
				)
				(justify right bottom mirror)
			)
		)
		(property "Datasheet" "https://www.murata.com/products/productdetail?partno=GRM155R61H104KE14%23"
			(at 0 0 90)
			(layer "F.Fab")
			(hide yes)
			(effects
				(font
					(size 1.27 1.27)
					(thickness 0.15)
				)
			)
		)
		(property "MPN" "GRM155R61H104KE14D"
			(at 0 0 90)
			(unlocked yes)
			(layer "B.Fab")
			(hide yes)
			(effects
				(font
					(size 1 1)
					(thickness 0.15)
				)
				(justify mirror)
			)
		)
		(property "Manufacturer" "Murata"
			(at 0 0 90)
			(unlocked yes)
			(layer "B.Fab")
			(hide yes)
			(effects
				(font
					(size 1 1)
					(thickness 0.15)
				)
				(justify mirror)
			)
		)
		(property "License" "Apache-2.0"
			(at 0 0 90)
			(unlocked yes)
			(layer "B.Fab")
			(hide yes)
			(effects
				(font
					(size 1 1)
					(thickness 0.15)
				)
				(justify mirror)
			)
		)
		(property "Author" "Antmicro"
			(at 0 0 90)
			(unlocked yes)
			(layer "B.Fab")
			(hide yes)
			(effects
				(font
					(size 1 1)
					(thickness 0.15)
				)
				(justify mirror)
			)
		)
		(property "Val" "100n"
			(at 0 0 90)
			(unlocked yes)
			(layer "B.Fab")
			(hide yes)
			(effects
				(font
					(size 1 1)
					(thickness 0.15)
				)
				(justify mirror)
			)
		)
		(property "Voltage" "50V"
			(at 0 0 90)
			(unlocked yes)
			(layer "B.Fab")
			(hide yes)
			(effects
				(font
					(size 1 1)
					(thickness 0.15)
				)
				(justify mirror)
			)
		)
		(property "Dielectric" "X5R"
			(at 0 0 90)
			(unlocked yes)
			(layer "B.Fab")
			(hide yes)
			(effects
				(font
					(size 1 1)
					(thickness 0.15)
				)
				(justify mirror)
			)
		)
		(sheetname "/FPGA power/")
		(sheetfile "fpga-power.kicad_sch")
		(attr smd)
		(fp_rect
			(start -0.95 0.45)
			(end 0.95 -0.45)
			(stroke
				(width 0.05)
				(type default)
			)
			(fill no)
			(layer "B.CrtYd")
		)
		(fp_line
			(start 0.498 -0.248)
			(end -0.5 -0.248)
			(stroke
				(width 0.15)
				(type solid)
			)
			(layer "B.Fab")
		)
		(fp_line
			(start -0.5 -0.248)
			(end -0.5 0.25)
			(stroke
				(width 0.15)
				(type solid)
			)
			(layer "B.Fab")
		)
		(fp_line
			(start 0.498 0.25)
			(end 0.498 -0.248)
			(stroke
				(width 0.15)
				(type solid)
			)
			(layer "B.Fab")
		)
		(fp_line
			(start -0.5 0.25)
			(end 0.498 0.25)
			(stroke
				(width 0.15)
				(type solid)
			)
			(layer "B.Fab")
		)
		(fp_text user "${REFERENCE}"
			(at -0.9656 -3.169 270)
			(layer "B.Fab")
			(effects
				(font
					(size 0.7 0.7)
					(thickness 0.15)
				)
				(justify left bottom mirror)
			)
		)
		(fp_text user "License: Apache-2.0"
			(at -0.9656 -4.369 270)
			(layer "B.Fab")
			(effects
				(font
					(size 0.7 0.7)
					(thickness 0.15)
				)
				(justify left bottom mirror)
			)
		)
		(fp_text user "Author: Antmicro"
			(at -0.9656 -5.569 270)
			(layer "B.Fab")
			(effects
				(font
					(size 0.7 0.7)
					(thickness 0.15)
				)
				(justify left bottom mirror)
			)
		)
		(pad "1" smd roundrect
			(at -0.5 0)
			(size 0.6 0.6)
			(layers "B.Cu" "B.Mask" "B.Paste")
			(roundrect_rratio 0.25)
			(net 1 "GND")
			(pintype "passive")
		)
		(pad "2" smd roundrect
			(at 0.498 0 90)
			(size 0.6 0.6)
			(layers "B.Cu" "B.Mask" "B.Paste")
			(roundrect_rratio 0.25)
			(net 820 "+0V9_MGTAVCC")
			(pintype "passive")
		)
	)
	(footprint "antmicro-footprints:R_0402_1005Metric_EIA"
		(layer "B.Cu")
		(at 194 143.5 90)
		(descr "Resistor SMD 0402 (1005 Metric), square (rectangular) end terminal, IPC_7351 nominal, (Body size source: IPC-SM-782 page 76, https://www.pcb-3d.com/wordpress/wp-content/uploads/ipc-sm-782a_amendment_1_and_2.pdf)")
		(tags "resistor 0402")
		(property "Reference" "R134"
			(at -1.5 1.5 90)
			(layer "B.SilkS")
			(effects
				(font
					(size 0.7 0.7)
					(thickness 0.15)
				)
				(justify right bottom mirror)
			)
		)
		(property "Value" "R_240R_0402"
			(at 0 -1.169 90)
			(layer "B.Fab")
			(effects
				(font
					(size 0.7 0.7)
					(thickness 0.15)
				)
				(justify right bottom mirror)
			)
		)
		(property "Datasheet" "https://www.bourns.com/docs/product-datasheets/cr.pdf"
			(at 0 0 90)
			(layer "F.Fab")
			(hide yes)
			(effects
				(font
					(size 1.27 1.27)
					(thickness 0.15)
				)
			)
		)
		(property "MPN" "CR0402-FX-2400GLF"
			(at 0 0 90)
			(unlocked yes)
			(layer "B.Fab")
			(hide yes)
			(effects
				(font
					(size 1 1)
					(thickness 0.15)
				)
				(justify mirror)
			)
		)
		(property "Manufacturer" "Bourns"
			(at 0 0 90)
			(unlocked yes)
			(layer "B.Fab")
			(hide yes)
			(effects
				(font
					(size 1 1)
					(thickness 0.15)
				)
				(justify mirror)
			)
		)
		(property "License" "Apache-2.0"
			(at 0 0 90)
			(unlocked yes)
			(layer "B.Fab")
			(hide yes)
			(effects
				(font
					(size 1 1)
					(thickness 0.15)
				)
				(justify mirror)
			)
		)
		(property "Author" "Antmicro"
			(at 0 0 90)
			(unlocked yes)
			(layer "B.Fab")
			(hide yes)
			(effects
				(font
					(size 1 1)
					(thickness 0.15)
				)
				(justify mirror)
			)
		)
		(property "Val" "240R"
			(at 0 0 90)
			(unlocked yes)
			(layer "B.Fab")
			(hide yes)
			(effects
				(font
					(size 1 1)
					(thickness 0.15)
				)
				(justify mirror)
			)
		)
		(property "Tolerance" "1%"
			(at 0 0 90)
			(unlocked yes)
			(layer "B.Fab")
			(hide yes)
			(effects
				(font
					(size 1 1)
					(thickness 0.15)
				)
				(justify mirror)
			)
		)
		(sheetname "/FPGA banks HP/")
		(sheetfile "fpga-hp-banks.kicad_sch")
		(attr smd)
		(fp_rect
			(start -0.95 0.45)
			(end 0.95 -0.45)
			(stroke
				(width 0.05)
				(type default)
			)
			(fill no)
			(layer "B.CrtYd")
		)
		(fp_line
			(start 0.499 -0.249)
			(end -0.5 -0.249)
			(stroke
				(width 0.15)
				(type solid)
			)
			(layer "B.Fab")
		)
		(fp_line
			(start -0.5 -0.249)
			(end -0.5 0.25)
			(stroke
				(width 0.15)
				(type solid)
			)
			(layer "B.Fab")
		)
		(fp_line
			(start 0.499 0.25)
			(end 0.499 -0.249)
			(stroke
				(width 0.15)
				(type solid)
			)
			(layer "B.Fab")
		)
		(fp_line
			(start -0.5 0.25)
			(end 0.499 0.25)
			(stroke
				(width 0.15)
				(type solid)
			)
			(layer "B.Fab")
		)
		(fp_text user "Author: Antmicro"
			(at -0.95 -5.569 270)
			(layer "B.Fab")
			(effects
				(font
					(size 0.7 0.7)
					(thickness 0.15)
				)
				(justify left bottom mirror)
			)
		)
		(fp_text user "${REFERENCE}"
			(at -0.95 -3.169 270)
			(layer "B.Fab")
			(effects
				(font
					(size 0.7 0.7)
					(thickness 0.15)
				)
				(justify left bottom mirror)
			)
		)
		(fp_text user "License: Apache-2.0"
			(at -0.95 -4.369 270)
			(layer "B.Fab")
			(effects
				(font
					(size 0.7 0.7)
					(thickness 0.15)
				)
				(justify left bottom mirror)
			)
		)
		(pad "1" smd roundrect
			(at -0.5 0)
			(size 0.6 0.6)
			(layers "B.Cu" "B.Mask" "B.Paste")
			(roundrect_rratio 0.25)
			(net 548 "/FPGA banks HP/VRP_65")
			(pintype "passive")
		)
		(pad "2" smd roundrect
			(at 0.499 0 90)
			(size 0.6 0.6)
			(layers "B.Cu" "B.Mask" "B.Paste")
			(roundrect_rratio 0.25)
			(net 1 "GND")
			(pintype "passive")
		)
	)
	(footprint "antmicro-footprints:NetTie-2_SMD_Pad0.127mm"
		(layer "B.Cu")
		(at 205.823 151.15 180)
		(descr "Net tie, 2 pin, 0.127mm  SMD pads")
		(tags "net tie")
		(property "Reference" "TP4"
			(at -0.128 1.345 0)
			(layer "B.SilkS")
			(hide yes)
			(effects
				(font
					(size 0.7 0.7)
					(thickness 0.15)
				)
				(justify left bottom mirror)
			)
		)
		(property "Value" "Net-Tie_P0.127mm"
			(at 0 -1.199 0)
			(layer "B.Fab")
			(effects
				(font
					(size 0.7 0.7)
					(thickness 0.15)
				)
				(justify left bottom mirror)
			)
		)
		(property "MPN" ""
			(at 0 0 180)
			(unlocked yes)
			(layer "B.Fab")
			(hide yes)
			(effects
				(font
					(size 1 1)
					(thickness 0.15)
				)
				(justify mirror)
			)
		)
		(property "Manufacturer" ""
			(at 0 0 180)
			(unlocked yes)
			(layer "B.Fab")
			(hide yes)
			(effects
				(font
					(size 1 1)
					(thickness 0.15)
				)
				(justify mirror)
			)
		)
		(property "Author" "Antmicro"
			(at 0 0 180)
			(unlocked yes)
			(layer "B.Fab")
			(hide yes)
			(effects
				(font
					(size 1 1)
					(thickness 0.15)
				)
				(justify mirror)
			)
		)
		(property "License" "Apache-2.0"
			(at 0 0 180)
			(unlocked yes)
			(layer "B.Fab")
			(hide yes)
			(effects
				(font
					(size 1 1)
					(thickness 0.15)
				)
				(justify mirror)
			)
		)
		(property ki_fp_filters "Net*Tie*")
		(sheetname "/FPGA Config/")
		(sheetfile "fpga-config.kicad_sch")
		(attr through_hole exclude_from_pos_files exclude_from_bom)
		(net_tie_pad_groups "1, 2")
		(fp_poly
			(pts
				(xy -0.0635 0.0635) (xy 0.0625 0.0635) (xy 0.0625 -0.0635) (xy -0.0635 -0.0635)
			)
			(stroke
				(width 0)
				(type solid)
			)
			(fill yes)
			(layer "B.Cu")
		)
		(fp_poly
			(pts
				(xy 0.2 0.16) (xy 0.29 0.07) (xy 0.29 -0.07) (xy 0.2 -0.16) (xy -0.2 -0.16) (xy -0.29 -0.07) (xy -0.29 0.06)
				(xy -0.19 0.16)
			)
			(stroke
				(width 0.05)
				(type solid)
			)
			(fill no)
			(layer "B.CrtYd")
		)
		(fp_text user "Author: Antmicro"
			(at -0.128 -4.4 0)
			(layer "B.Fab")
			(effects
				(font
					(size 0.7 0.7)
					(thickness 0.15)
				)
				(justify left bottom mirror)
			)
		)
		(fp_text user "${REFERENCE}"
			(at -0.128 -3.2 0)
			(layer "B.Fab")
			(effects
				(font
					(size 0.7 0.7)
					(thickness 0.15)
				)
				(justify left bottom mirror)
			)
		)
		(fp_text user "License: Apache-2.0"
			(at -0.128 -5.6 0)
			(layer "B.Fab")
			(effects
				(font
					(size 0.7 0.7)
					(thickness 0.15)
				)
				(justify left bottom mirror)
			)
		)
		(pad "1" smd roundrect
			(at -0.127 0)
			(size 0.127 0.127)
			(layers "B.Cu")
			(roundrect_rratio 0.5)
			(chamfer_ratio 0)
			(chamfer top_left bottom_left)
			(net 1 "GND")
			(pinfunction "1")
			(pintype "passive")
		)
		(pad "2" smd roundrect
			(at 0.126 0 180)
			(size 0.127 0.127)
			(layers "B.Cu")
			(roundrect_rratio 0.5)
			(chamfer_ratio 0)
			(chamfer top_left bottom_left)
			(net 598 "/FPGA Config/VREFN")
			(pinfunction "2")
			(pintype "passive")
		)
	)
)
